(kicad_pcb
	(version 20260206)
	(generator "pcbnew")
	(generator_version "10.0")
	(general
		(thickness 1.6)
		(legacy_teardrops no)
	)
	(paper "A4")
	(title_block
		(title "01162023_DA0F0TEBIF0_F0T_Expander_BD_F_brd_V02_OCP.brd")
		(comment 1 "Grand Teton / footprints 2294-2301 of 9728")
	)
	(layers
		(0 "F.Cu" signal "TOP")
		(4 "In1.Cu" signal "GND")
		(6 "In2.Cu" signal "VCC")
		(8 "In3.Cu" signal "VCC1")
		(10 "In4.Cu" signal "GND1")
		(12 "In5.Cu" signal "IN1")
		(14 "In6.Cu" signal "GND2")
		(16 "In7.Cu" signal "IN2")
		(18 "In8.Cu" signal "GND3")
		(20 "In9.Cu" signal "IN3")
		(22 "In10.Cu" signal "GND4")
		(24 "In11.Cu" signal "IN4")
		(26 "In12.Cu" signal "GND5")
		(28 "In13.Cu" signal "IN5")
		(30 "In14.Cu" signal "GND6")
		(32 "In15.Cu" signal "IN6")
		(34 "In16.Cu" signal "GND7")
		(2 "B.Cu" signal "BOTTOM")
		(9 "F.Adhes" user "F.Adhesive")
		(11 "B.Adhes" user "B.Adhesive")
		(13 "F.Paste" user "Package Geometry/Pastemask Top")
		(15 "B.Paste" user "Package Geometry/Pastemask Bottom")
		(5 "F.SilkS" user "Ref Des/Silkscreen Top")
		(7 "B.SilkS" user "Ref Des/Silkscreen Bottom")
		(1 "F.Mask" user "Board Geometry/Soldermask Top")
		(3 "B.Mask" user "Board Geometry/Soldermask Bottom")
		(17 "Dwgs.User" user "User.Drawings")
		(19 "Cmts.User" user "User.Comments")
		(21 "Eco1.User" user "User.Eco1")
		(23 "Eco2.User" user "User.Eco2")
		(25 "Edge.Cuts" user "Board Geometry/Outline")
		(27 "Margin" user)
		(31 "F.CrtYd" user "Package Geometry/Place Bound Top")
		(29 "B.CrtYd" user "Package Geometry/Place Bound Bottom")
		(35 "F.Fab" user "Ref Des/Assembly Top")
		(33 "B.Fab" user "Ref Des/Assembly Bottom")
	)
	(footprint ""
		(layer "F.Cu")
		(at 112.973866 -161.405824 90)
		(property "Reference" "PR63"
			(at 0 0 90)
			(layer "F.SilkS")
			(hide yes)
			(effects
				(font
					(size 1.27 1.27)
				)
			)
		)
		(property "Value" ""
			(at 0 0 90)
			(layer "F.Fab")
			(effects
				(font
					(size 1.27 1.27)
				)
			)
		)
		(duplicate_pad_numbers_are_jumpers no)
		(fp_line
			(start 0.7874 -0.4064)
			(end 0.7874 0.4064)
			(stroke
				(width 0.1524)
				(type default)
			)
			(layer "F.SilkS")
		)
		(fp_line
			(start -0.7874 -0.4064)
			(end 0.7874 -0.4064)
			(stroke
				(width 0.1524)
				(type default)
			)
			(layer "F.SilkS")
		)
		(fp_line
			(start 0.7874 0.4064)
			(end -0.7874 0.4064)
			(stroke
				(width 0.1524)
				(type default)
			)
			(layer "F.SilkS")
		)
		(fp_line
			(start -0.7874 0.4064)
			(end -0.7874 -0.4064)
			(stroke
				(width 0.1524)
				(type default)
			)
			(layer "F.SilkS")
		)
		(fp_line
			(start -0.12065 -0.305054)
			(end -0.12065 -0.2794)
			(stroke
				(width 0.1)
				(type default)
			)
			(layer "F.Fab")
		)
		(fp_line
			(start -0.67945 -0.305054)
			(end -0.12065 -0.305054)
			(stroke
				(width 0.1)
				(type default)
			)
			(layer "F.Fab")
		)
		(fp_line
			(start 0.67945 -0.3048)
			(end 0.67945 0.3048)
			(stroke
				(width 0.1)
				(type default)
			)
			(layer "F.Fab")
		)
		(fp_line
			(start 0.12065 -0.3048)
			(end 0.67945 -0.3048)
			(stroke
				(width 0.1)
				(type default)
			)
			(layer "F.Fab")
		)
		(fp_line
			(start 0.12065 -0.2794)
			(end 0.12065 -0.3048)
			(stroke
				(width 0.1)
				(type default)
			)
			(layer "F.Fab")
		)
		(fp_line
			(start -0.12065 -0.2794)
			(end 0.12065 -0.2794)
			(stroke
				(width 0.1)
				(type default)
			)
			(layer "F.Fab")
		)
		(fp_line
			(start 0.120396 0.2794)
			(end -0.12065 0.2794)
			(stroke
				(width 0.1)
				(type default)
			)
			(layer "F.Fab")
		)
		(fp_line
			(start -0.12065 0.2794)
			(end -0.12065 0.3048)
			(stroke
				(width 0.1)
				(type default)
			)
			(layer "F.Fab")
		)
		(fp_line
			(start 0.67945 0.3048)
			(end 0.120396 0.3048)
			(stroke
				(width 0.1)
				(type default)
			)
			(layer "F.Fab")
		)
		(fp_line
			(start 0.120396 0.3048)
			(end 0.120396 0.2794)
			(stroke
				(width 0.1)
				(type default)
			)
			(layer "F.Fab")
		)
		(fp_line
			(start -0.12065 0.3048)
			(end -0.67945 0.3048)
			(stroke
				(width 0.1)
				(type default)
			)
			(layer "F.Fab")
		)
		(fp_line
			(start -0.67945 0.3048)
			(end -0.67945 -0.305054)
			(stroke
				(width 0.1)
				(type default)
			)
			(layer "F.Fab")
		)
		(pad "1" smd circle
			(at -0.40005 0 90)
			(size 0 0)
			(layers "F.Cu" "F.Mask" "F.Paste")
			(net "GND")
		)
		(pad "2" smd circle
			(at 0.40005 0 90)
			(size 0 0)
			(layers "F.Cu" "F.Mask" "F.Paste")
			(net "P3V3_AUX_FB")
		)
	)
	(footprint ""
		(layer "F.Cu")
		(at 177.705512 -343.952322 90)
		(property "Reference" "C2526"
			(at 0 0 90)
			(layer "F.SilkS")
			(hide yes)
			(effects
				(font
					(size 1.27 1.27)
				)
			)
		)
		(property "Value" ""
			(at 0 0 90)
			(layer "F.Fab")
			(effects
				(font
					(size 1.27 1.27)
				)
			)
		)
		(duplicate_pad_numbers_are_jumpers no)
		(fp_line
			(start 0.299974 -0.150114)
			(end 0.299974 0.150114)
			(stroke
				(width 0.1)
				(type default)
			)
			(layer "F.Fab")
		)
		(fp_line
			(start -0.299974 -0.150114)
			(end 0.299974 -0.150114)
			(stroke
				(width 0.1)
				(type default)
			)
			(layer "F.Fab")
		)
		(fp_line
			(start 0.299974 0.150114)
			(end -0.299974 0.150114)
			(stroke
				(width 0.1)
				(type default)
			)
			(layer "F.Fab")
		)
		(fp_line
			(start -0.299974 0.150114)
			(end -0.299974 -0.150114)
			(stroke
				(width 0.1)
				(type default)
			)
			(layer "F.Fab")
		)
		(pad "1" smd rect
			(at -0.2667 0 90)
			(size 0.3048 0.381)
			(layers "F.Cu" "F.Mask" "F.Paste")
			(net "P5E_PEX1_STN4_TX_DP<72>")
		)
		(pad "2" smd rect
			(at 0.2667 0 90)
			(size 0.3048 0.381)
			(layers "F.Cu" "F.Mask" "F.Paste")
			(net "P5E_PEX1_STN4_TX_C_DP<72>")
		)
	)
	(footprint ""
		(layer "F.Cu")
		(at 61.82995 -171.661328 180)
		(property "Reference" "C859"
			(at 0 0 180)
			(layer "F.SilkS")
			(hide yes)
			(effects
				(font
					(size 1.27 1.27)
				)
			)
		)
		(property "Value" ""
			(at 0 0 180)
			(layer "F.Fab")
			(effects
				(font
					(size 1.27 1.27)
				)
			)
		)
		(duplicate_pad_numbers_are_jumpers no)
		(fp_line
			(start 0.7874 0.4064)
			(end -0.7874 0.4064)
			(stroke
				(width 0.1524)
				(type default)
			)
			(layer "F.SilkS")
		)
		(fp_line
			(start 0.7874 -0.4064)
			(end 0.7874 0.4064)
			(stroke
				(width 0.1524)
				(type default)
			)
			(layer "F.SilkS")
		)
		(fp_line
			(start -0.7874 0.4064)
			(end -0.7874 -0.4064)
			(stroke
				(width 0.1524)
				(type default)
			)
			(layer "F.SilkS")
		)
		(fp_line
			(start -0.7874 -0.4064)
			(end 0.7874 -0.4064)
			(stroke
				(width 0.1524)
				(type default)
			)
			(layer "F.SilkS")
		)
		(fp_line
			(start 0.67945 0.3048)
			(end 0.120396 0.3048)
			(stroke
				(width 0.1)
				(type default)
			)
			(layer "F.Fab")
		)
		(fp_line
			(start 0.67945 -0.3048)
			(end 0.67945 0.3048)
			(stroke
				(width 0.1)
				(type default)
			)
			(layer "F.Fab")
		)
		(fp_line
			(start 0.12065 -0.2794)
			(end 0.12065 -0.3048)
			(stroke
				(width 0.1)
				(type default)
			)
			(layer "F.Fab")
		)
		(fp_line
			(start 0.12065 -0.3048)
			(end 0.67945 -0.3048)
			(stroke
				(width 0.1)
				(type default)
			)
			(layer "F.Fab")
		)
		(fp_line
			(start 0.120396 0.3048)
			(end 0.120396 0.2794)
			(stroke
				(width 0.1)
				(type default)
			)
			(layer "F.Fab")
		)
		(fp_line
			(start 0.120396 0.2794)
			(end -0.12065 0.2794)
			(stroke
				(width 0.1)
				(type default)
			)
			(layer "F.Fab")
		)
		(fp_line
			(start -0.12065 0.3048)
			(end -0.67945 0.3048)
			(stroke
				(width 0.1)
				(type default)
			)
			(layer "F.Fab")
		)
		(fp_line
			(start -0.12065 0.2794)
			(end -0.12065 0.3048)
			(stroke
				(width 0.1)
				(type default)
			)
			(layer "F.Fab")
		)
		(fp_line
			(start -0.12065 -0.2794)
			(end 0.12065 -0.2794)
			(stroke
				(width 0.1)
				(type default)
			)
			(layer "F.Fab")
		)
		(fp_line
			(start -0.12065 -0.305054)
			(end -0.12065 -0.2794)
			(stroke
				(width 0.1)
				(type default)
			)
			(layer "F.Fab")
		)
		(fp_line
			(start -0.67945 0.3048)
			(end -0.67945 -0.305054)
			(stroke
				(width 0.1)
				(type default)
			)
			(layer "F.Fab")
		)
		(fp_line
			(start -0.67945 -0.305054)
			(end -0.12065 -0.305054)
			(stroke
				(width 0.1)
				(type default)
			)
			(layer "F.Fab")
		)
		(pad "1" smd circle
			(at -0.40005 0 180)
			(size 0 0)
			(layers "F.Cu" "F.Mask" "F.Paste")
			(net "P3V3_NIC0")
		)
		(pad "2" smd circle
			(at 0.40005 0 180)
			(size 0 0)
			(layers "F.Cu" "F.Mask" "F.Paste")
			(net "GND")
		)
	)
	(footprint ""
		(layer "F.Cu")
		(at 311.514744 -81.36001 -90)
		(property "Reference" "R306"
			(at 0 0 270)
			(layer "F.SilkS")
			(hide yes)
			(effects
				(font
					(size 1.27 1.27)
				)
			)
		)
		(property "Value" ""
			(at 0 0 270)
			(layer "F.Fab")
			(effects
				(font
					(size 1.27 1.27)
				)
			)
		)
		(duplicate_pad_numbers_are_jumpers no)
		(fp_line
			(start -0.7874 0.4064)
			(end -0.7874 -0.4064)
			(stroke
				(width 0.1524)
				(type default)
			)
			(layer "F.SilkS")
		)
		(fp_line
			(start 0.7874 0.4064)
			(end -0.7874 0.4064)
			(stroke
				(width 0.1524)
				(type default)
			)
			(layer "F.SilkS")
		)
		(fp_line
			(start -0.7874 -0.4064)
			(end 0.7874 -0.4064)
			(stroke
				(width 0.1524)
				(type default)
			)
			(layer "F.SilkS")
		)
		(fp_line
			(start 0.7874 -0.4064)
			(end 0.7874 0.4064)
			(stroke
				(width 0.1524)
				(type default)
			)
			(layer "F.SilkS")
		)
		(fp_line
			(start -0.67945 0.3048)
			(end -0.67945 -0.305054)
			(stroke
				(width 0.1)
				(type default)
			)
			(layer "F.Fab")
		)
		(fp_line
			(start -0.12065 0.3048)
			(end -0.67945 0.3048)
			(stroke
				(width 0.1)
				(type default)
			)
			(layer "F.Fab")
		)
		(fp_line
			(start 0.120396 0.3048)
			(end 0.120396 0.2794)
			(stroke
				(width 0.1)
				(type default)
			)
			(layer "F.Fab")
		)
		(fp_line
			(start 0.67945 0.3048)
			(end 0.120396 0.3048)
			(stroke
				(width 0.1)
				(type default)
			)
			(layer "F.Fab")
		)
		(fp_line
			(start -0.12065 0.2794)
			(end -0.12065 0.3048)
			(stroke
				(width 0.1)
				(type default)
			)
			(layer "F.Fab")
		)
		(fp_line
			(start 0.120396 0.2794)
			(end -0.12065 0.2794)
			(stroke
				(width 0.1)
				(type default)
			)
			(layer "F.Fab")
		)
		(fp_line
			(start -0.12065 -0.2794)
			(end 0.12065 -0.2794)
			(stroke
				(width 0.1)
				(type default)
			)
			(layer "F.Fab")
		)
		(fp_line
			(start 0.12065 -0.2794)
			(end 0.12065 -0.3048)
			(stroke
				(width 0.1)
				(type default)
			)
			(layer "F.Fab")
		)
		(fp_line
			(start 0.12065 -0.3048)
			(end 0.67945 -0.3048)
			(stroke
				(width 0.1)
				(type default)
			)
			(layer "F.Fab")
		)
		(fp_line
			(start 0.67945 -0.3048)
			(end 0.67945 0.3048)
			(stroke
				(width 0.1)
				(type default)
			)
			(layer "F.Fab")
		)
		(fp_line
			(start -0.67945 -0.305054)
			(end -0.12065 -0.305054)
			(stroke
				(width 0.1)
				(type default)
			)
			(layer "F.Fab")
		)
		(fp_line
			(start -0.12065 -0.305054)
			(end -0.12065 -0.2794)
			(stroke
				(width 0.1)
				(type default)
			)
			(layer "F.Fab")
		)
		(pad "1" smd circle
			(at -0.40005 0 270)
			(size 0 0)
			(layers "F.Cu" "F.Mask" "F.Paste")
			(net "HP_NIC5_PWRGD_R")
		)
		(pad "2" smd circle
			(at 0.40005 0 270)
			(size 0 0)
			(layers "F.Cu" "F.Mask" "F.Paste")
			(net "HP_NIC5_PWRGD")
		)
	)
	(footprint ""
		(layer "F.Cu")
		(at 330.27239 -8.177022 90)
		(property "Reference" "C2734"
			(at 0 0 90)
			(layer "F.SilkS")
			(hide yes)
			(effects
				(font
					(size 1.27 1.27)
				)
			)
		)
		(property "Value" ""
			(at 0 0 90)
			(layer "F.Fab")
			(effects
				(font
					(size 1.27 1.27)
				)
			)
		)
		(duplicate_pad_numbers_are_jumpers no)
		(fp_line
			(start 0.7874 -0.4064)
			(end 0.7874 0.4064)
			(stroke
				(width 0.1524)
				(type default)
			)
			(layer "F.SilkS")
		)
		(fp_line
			(start -0.7874 -0.4064)
			(end 0.7874 -0.4064)
			(stroke
				(width 0.1524)
				(type default)
			)
			(layer "F.SilkS")
		)
		(fp_line
			(start 0.7874 0.4064)
			(end -0.7874 0.4064)
			(stroke
				(width 0.1524)
				(type default)
			)
			(layer "F.SilkS")
		)
		(fp_line
			(start -0.7874 0.4064)
			(end -0.7874 -0.4064)
			(stroke
				(width 0.1524)
				(type default)
			)
			(layer "F.SilkS")
		)
		(fp_line
			(start -0.12065 -0.305054)
			(end -0.12065 -0.2794)
			(stroke
				(width 0.1)
				(type default)
			)
			(layer "F.Fab")
		)
		(fp_line
			(start -0.67945 -0.305054)
			(end -0.12065 -0.305054)
			(stroke
				(width 0.1)
				(type default)
			)
			(layer "F.Fab")
		)
		(fp_line
			(start 0.67945 -0.3048)
			(end 0.67945 0.3048)
			(stroke
				(width 0.1)
				(type default)
			)
			(layer "F.Fab")
		)
		(fp_line
			(start 0.12065 -0.3048)
			(end 0.67945 -0.3048)
			(stroke
				(width 0.1)
				(type default)
			)
			(layer "F.Fab")
		)
		(fp_line
			(start 0.12065 -0.2794)
			(end 0.12065 -0.3048)
			(stroke
				(width 0.1)
				(type default)
			)
			(layer "F.Fab")
		)
		(fp_line
			(start -0.12065 -0.2794)
			(end 0.12065 -0.2794)
			(stroke
				(width 0.1)
				(type default)
			)
			(layer "F.Fab")
		)
		(fp_line
			(start 0.120396 0.2794)
			(end -0.12065 0.2794)
			(stroke
				(width 0.1)
				(type default)
			)
			(layer "F.Fab")
		)
		(fp_line
			(start -0.12065 0.2794)
			(end -0.12065 0.3048)
			(stroke
				(width 0.1)
				(type default)
			)
			(layer "F.Fab")
		)
		(fp_line
			(start 0.67945 0.3048)
			(end 0.120396 0.3048)
			(stroke
				(width 0.1)
				(type default)
			)
			(layer "F.Fab")
		)
		(fp_line
			(start 0.120396 0.3048)
			(end 0.120396 0.2794)
			(stroke
				(width 0.1)
				(type default)
			)
			(layer "F.Fab")
		)
		(fp_line
			(start -0.12065 0.3048)
			(end -0.67945 0.3048)
			(stroke
				(width 0.1)
				(type default)
			)
			(layer "F.Fab")
		)
		(fp_line
			(start -0.67945 0.3048)
			(end -0.67945 -0.305054)
			(stroke
				(width 0.1)
				(type default)
			)
			(layer "F.Fab")
		)
		(pad "1" smd circle
			(at -0.40005 0 90)
			(size 0 0)
			(layers "F.Cu" "F.Mask" "F.Paste")
			(net "GND")
		)
		(pad "2" smd circle
			(at 0.40005 0 90)
			(size 0 0)
			(layers "F.Cu" "F.Mask" "F.Paste")
			(net "P3V3_SSD11")
		)
	)
	(footprint ""
		(layer "F.Cu")
		(at 136.534652 -33.631886 180)
		(property "Reference" "C277"
			(at 0 0 180)
			(layer "F.SilkS")
			(hide yes)
			(effects
				(font
					(size 1.27 1.27)
				)
			)
		)
		(property "Value" ""
			(at 0 0 180)
			(layer "F.Fab")
			(effects
				(font
					(size 1.27 1.27)
				)
			)
		)
		(duplicate_pad_numbers_are_jumpers no)
		(fp_line
			(start 0.299974 0.150114)
			(end -0.299974 0.150114)
			(stroke
				(width 0.1)
				(type default)
			)
			(layer "F.Fab")
		)
		(fp_line
			(start 0.299974 -0.150114)
			(end 0.299974 0.150114)
			(stroke
				(width 0.1)
				(type default)
			)
			(layer "F.Fab")
		)
		(fp_line
			(start -0.299974 0.150114)
			(end -0.299974 -0.150114)
			(stroke
				(width 0.1)
				(type default)
			)
			(layer "F.Fab")
		)
		(fp_line
			(start -0.299974 -0.150114)
			(end 0.299974 -0.150114)
			(stroke
				(width 0.1)
				(type default)
			)
			(layer "F.Fab")
		)
		(pad "1" smd rect
			(at -0.2667 0 180)
			(size 0.3048 0.381)
			(layers "F.Cu" "F.Mask" "F.Paste")
			(net "P5E_PEX1_STN2_TX_DN<47>")
		)
		(pad "2" smd rect
			(at 0.2667 0 180)
			(size 0.3048 0.381)
			(layers "F.Cu" "F.Mask" "F.Paste")
			(net "P5E_PEX1_STN2_TX_C_DN<47>")
		)
	)
	(footprint ""
		(layer "F.Cu")
		(at 427.923452 -356.244906 90)
		(property "Reference" "C807"
			(at 0 0 90)
			(layer "F.SilkS")
			(hide yes)
			(effects
				(font
					(size 1.27 1.27)
				)
			)
		)
		(property "Value" ""
			(at 0 0 90)
			(layer "F.Fab")
			(effects
				(font
					(size 1.27 1.27)
				)
			)
		)
		(duplicate_pad_numbers_are_jumpers no)
		(fp_line
			(start 0.299974 -0.150114)
			(end 0.299974 0.150114)
			(stroke
				(width 0.1)
				(type default)
			)
			(layer "F.Fab")
		)
		(fp_line
			(start -0.299974 -0.150114)
			(end 0.299974 -0.150114)
			(stroke
				(width 0.1)
				(type default)
			)
			(layer "F.Fab")
		)
		(fp_line
			(start 0.299974 0.150114)
			(end -0.299974 0.150114)
			(stroke
				(width 0.1)
				(type default)
			)
			(layer "F.Fab")
		)
		(fp_line
			(start -0.299974 0.150114)
			(end -0.299974 -0.150114)
			(stroke
				(width 0.1)
				(type default)
			)
			(layer "F.Fab")
		)
		(pad "1" smd rect
			(at -0.2667 0 90)
			(size 0.3048 0.381)
			(layers "F.Cu" "F.Mask" "F.Paste")
			(net "P5E_PEX3_STN7_TX_DN<121>")
		)
		(pad "2" smd rect
			(at 0.2667 0 90)
			(size 0.3048 0.381)
			(layers "F.Cu" "F.Mask" "F.Paste")
			(net "P5E_PEX3_STN7_TX_C_DN<121>")
		)
	)
	(footprint ""
		(layer "F.Cu")
		(at 231.844596 -273.471386)
		(property "Reference" "R780"
			(at 0 0 0)
			(layer "F.SilkS")
			(hide yes)
			(effects
				(font
					(size 1.27 1.27)
				)
			)
		)
		(property "Value" ""
			(at 0 0 0)
			(layer "F.Fab")
			(effects
				(font
					(size 1.27 1.27)
				)
			)
		)
		(duplicate_pad_numbers_are_jumpers no)
		(fp_line
			(start -0.7874 -0.4064)
			(end 0.7874 -0.4064)
			(stroke
				(width 0.1524)
				(type default)
			)
			(layer "F.SilkS")
		)
		(fp_line
			(start -0.7874 0.4064)
			(end -0.7874 -0.4064)
			(stroke
				(width 0.1524)
				(type default)
			)
			(layer "F.SilkS")
		)
		(fp_line
			(start 0.7874 -0.4064)
			(end 0.7874 0.4064)
			(stroke
				(width 0.1524)
				(type default)
			)
			(layer "F.SilkS")
		)
		(fp_line
			(start 0.7874 0.4064)
			(end -0.7874 0.4064)
			(stroke
				(width 0.1524)
				(type default)
			)
			(layer "F.SilkS")
		)
		(fp_line
			(start -0.67945 -0.305054)
			(end -0.12065 -0.305054)
			(stroke
				(width 0.1)
				(type default)
			)
			(layer "F.Fab")
		)
		(fp_line
			(start -0.67945 0.3048)
			(end -0.67945 -0.305054)
			(stroke
				(width 0.1)
				(type default)
			)
			(layer "F.Fab")
		)
		(fp_line
			(start -0.12065 -0.305054)
			(end -0.12065 -0.2794)
			(stroke
				(width 0.1)
				(type default)
			)
			(layer "F.Fab")
		)
		(fp_line
			(start -0.12065 -0.2794)
			(end 0.12065 -0.2794)
			(stroke
				(width 0.1)
				(type default)
			)
			(layer "F.Fab")
		)
		(fp_line
			(start -0.12065 0.2794)
			(end -0.12065 0.3048)
			(stroke
				(width 0.1)
				(type default)
			)
			(layer "F.Fab")
		)
		(fp_line
			(start -0.12065 0.3048)
			(end -0.67945 0.3048)
			(stroke
				(width 0.1)
				(type default)
			)
			(layer "F.Fab")
		)
		(fp_line
			(start 0.120396 0.2794)
			(end -0.12065 0.2794)
			(stroke
				(width 0.1)
				(type default)
			)
			(layer "F.Fab")
		)
		(fp_line
			(start 0.120396 0.3048)
			(end 0.120396 0.2794)
			(stroke
				(width 0.1)
				(type default)
			)
			(layer "F.Fab")
		)
		(fp_line
			(start 0.12065 -0.3048)
			(end 0.67945 -0.3048)
			(stroke
				(width 0.1)
				(type default)
			)
			(layer "F.Fab")
		)
		(fp_line
			(start 0.12065 -0.2794)
			(end 0.12065 -0.3048)
			(stroke
				(width 0.1)
				(type default)
			)
			(layer "F.Fab")
		)
		(fp_line
			(start 0.67945 -0.3048)
			(end 0.67945 0.3048)
			(stroke
				(width 0.1)
				(type default)
			)
			(layer "F.Fab")
		)
		(fp_line
			(start 0.67945 0.3048)
			(end 0.120396 0.3048)
			(stroke
				(width 0.1)
				(type default)
			)
			(layer "F.Fab")
		)
		(pad "1" smd circle
			(at -0.40005 0)
			(size 0 0)
			(layers "F.Cu" "F.Mask" "F.Paste")
			(net "PEX1_P1V25_ADC_A1")
		)
		(pad "2" smd circle
			(at 0.40005 0)
			(size 0 0)
			(layers "F.Cu" "F.Mask" "F.Paste")
			(net "P3V3_AUX")
		)
	)
)
